(kicad_pcb
	(version 20260206)
	(generator "pcbnew")
	(generator_version "10.0")
	(general
		(thickness 1.6)
		(legacy_teardrops no)
	)
	(paper "A4")
	(title_block
		(title "fcb — 12433-1M.1206WZS1330.brd")
		(comment 1 "Open Vault / Knox (Wiwynn) / footprints 242-248 of 495")
	)
	(layers
		(0 "F.Cu" signal "TOP")
		(4 "In1.Cu" signal "L2GND")
		(6 "In2.Cu" signal "L3VCC")
		(2 "B.Cu" signal "BOTTOM")
		(9 "F.Adhes" user "F.Adhesive")
		(11 "B.Adhes" user "B.Adhesive")
		(13 "F.Paste" user "Package Geometry/Pastemask Top")
		(15 "B.Paste" user "Package Geometry/Pastemask Bottom")
		(5 "F.SilkS" user "Ref Des/Silkscreen Top")
		(7 "B.SilkS" user "Ref Des/Silkscreen Bottom")
		(1 "F.Mask" user "Board Geometry/Soldermask Top")
		(3 "B.Mask" user "Board Geometry/Soldermask Bottom")
		(17 "Dwgs.User" user "User.Drawings")
		(19 "Cmts.User" user "User.Comments")
		(21 "Eco1.User" user "User.Eco1")
		(23 "Eco2.User" user "User.Eco2")
		(25 "Edge.Cuts" user "Board Geometry/Outline")
		(27 "Margin" user)
		(31 "F.CrtYd" user "Package Geometry/Place Bound Top")
		(29 "B.CrtYd" user "Package Geometry/Place Bound Bottom")
		(35 "F.Fab" user "Ref Des/Assembly Top")
		(33 "B.Fab" user "Ref Des/Assembly Bottom")
	)
	(footprint ""
		(layer "F.Cu")
		(at 17.119092 -17.602962 180)
		(property "Reference" "R67"
			(at 0 0 180)
			(layer "F.SilkS")
			(hide yes)
			(effects
				(font
					(size 1.27 1.27)
				)
			)
		)
		(property "Value" "4K7R2F-GP"
			(at 0.064008 -3.993896 180)
			(unlocked yes)
			(layer "F.Fab")
			(hide yes)
			(effects
				(font
					(size 1.016 1.016)
					(thickness 0.1524)
				)
			)
		)
		(property "Device Type" "R402H16"
			(at 0.064008 -5.517896 180)
			(unlocked yes)
			(layer "F.Fab")
			(hide yes)
			(effects
				(font
					(size 1.016 1.016)
					(thickness 0.1524)
				)
			)
		)
		(duplicate_pad_numbers_are_jumpers no)
		(fp_line
			(start 0.508 -0.9398)
			(end -0.508 -0.9398)
			(stroke
				(width 0.1524)
				(type default)
			)
			(layer "F.SilkS")
		)
		(fp_line
			(start -0.508 -0.9398)
			(end -0.508 0.9398)
			(stroke
				(width 0.1524)
				(type default)
			)
			(layer "F.SilkS")
		)
		(fp_rect
			(start -0.508 0.9398)
			(end 0.508 -0.9398)
			(stroke
				(width 0)
				(type default)
			)
			(fill no)
			(layer "F.CrtYd")
		)
		(fp_rect
			(start -0.508 1.0668)
			(end 0.508 -0.8128)
			(stroke
				(width 0)
				(type default)
			)
			(fill no)
			(layer "F.Fab")
		)
		(pad "1" smd custom
			(at 0 -0.4445 180)
			(size 0.1397 0.1397)
			(layers "F.Cu" "F.Mask" "F.Paste")
			(net "P12V")
			(options
				(clearance outline)
				(anchor circle)
			)
			(primitives
				(gr_poly
					(pts
						(arc
							(start -0.1778 -0.2794)
							(mid -0.249642 -0.249642)
							(end -0.2794 -0.1778)
						)
						(arc
							(start -0.2794 0.1778)
							(mid -0.249642 0.249642)
							(end -0.1778 0.2794)
						)
						(arc
							(start 0.1778 0.2794)
							(mid 0.249642 0.249642)
							(end 0.2794 0.1778)
						)
						(arc
							(start 0.2794 -0.1778)
							(mid 0.249642 -0.249642)
							(end 0.1778 -0.2794)
						)
					)
					(width 0)
					(fill yes)
				)
			)
		)
		(pad "2" smd custom
			(at 0 0.4445 180)
			(size 0.1397 0.1397)
			(layers "F.Cu" "F.Mask" "F.Paste")
			(net "FAN_TACH12")
			(options
				(clearance outline)
				(anchor circle)
			)
			(primitives
				(gr_poly
					(pts
						(arc
							(start -0.1778 -0.2794)
							(mid -0.249642 -0.249642)
							(end -0.2794 -0.1778)
						)
						(arc
							(start -0.2794 0.1778)
							(mid -0.249642 0.249642)
							(end -0.1778 0.2794)
						)
						(arc
							(start 0.1778 0.2794)
							(mid 0.249642 0.249642)
							(end 0.2794 0.1778)
						)
						(arc
							(start 0.2794 -0.1778)
							(mid 0.249642 -0.249642)
							(end 0.1778 -0.2794)
						)
					)
					(width 0)
					(fill yes)
				)
			)
		)
	)
	(footprint ""
		(layer "F.Cu")
		(at 7.949946 -411.465014 -90)
		(property "Reference" "LED2"
			(at 0 0 270)
			(layer "F.SilkS")
			(hide yes)
			(effects
				(font
					(size 1.27 1.27)
				)
			)
		)
		(property "Value" "LED-RB-6-GP"
			(at -4.6736 3.8354 270)
			(unlocked yes)
			(layer "F.Fab")
			(hide yes)
			(effects
				(font
					(size 1.016 1.016)
					(thickness 0.1524)
				)
			)
		)
		(property "Device Type" "LED-100-3P-067106H325"
			(at -4.6736 2.3114 270)
			(unlocked yes)
			(layer "F.Fab")
			(hide yes)
			(effects
				(font
					(size 1.016 1.016)
					(thickness 0.1524)
				)
			)
		)
		(duplicate_pad_numbers_are_jumpers no)
		(fp_line
			(start -1.7526 10.414)
			(end -1.7526 6.6548)
			(stroke
				(width 0.1524)
				(type default)
			)
			(layer "F.SilkS")
		)
		(fp_line
			(start 1.7526 10.414)
			(end -1.7526 10.414)
			(stroke
				(width 0.1524)
				(type default)
			)
			(layer "F.SilkS")
		)
		(fp_line
			(start -3.6068 6.6548)
			(end -3.6068 -0.889)
			(stroke
				(width 0.1524)
				(type default)
			)
			(layer "F.SilkS")
		)
		(fp_line
			(start -1.7526 6.6548)
			(end -3.6068 6.6548)
			(stroke
				(width 0.1524)
				(type default)
			)
			(layer "F.SilkS")
		)
		(fp_line
			(start 1.7526 6.6548)
			(end 1.7526 10.414)
			(stroke
				(width 0.1524)
				(type default)
			)
			(layer "F.SilkS")
		)
		(fp_line
			(start 3.6068 6.6548)
			(end 1.7526 6.6548)
			(stroke
				(width 0.1524)
				(type default)
			)
			(layer "F.SilkS")
		)
		(fp_line
			(start -3.6068 -0.889)
			(end 3.6068 -0.889)
			(stroke
				(width 0.1524)
				(type default)
			)
			(layer "F.SilkS")
		)
		(fp_line
			(start 3.6068 -0.889)
			(end 3.6068 6.6548)
			(stroke
				(width 0.1524)
				(type default)
			)
			(layer "F.SilkS")
		)
		(fp_circle
			(center -2.54 0)
			(end -2.54 -0.9906)
			(stroke
				(width 0.3048)
				(type default)
			)
			(fill no)
			(layer "F.SilkS")
		)
		(fp_circle
			(center 0 0)
			(end 0 -0.9906)
			(stroke
				(width 0.3048)
				(type default)
			)
			(fill no)
			(layer "F.SilkS")
		)
		(fp_circle
			(center 2.54 0)
			(end 2.54 -0.9906)
			(stroke
				(width 0.3048)
				(type default)
			)
			(fill no)
			(layer "F.SilkS")
		)
		(fp_poly
			(pts
				(xy -1.4986 10.1473) (xy -1.4986 6.4008) (xy -3.3528 6.4008) (xy -3.3528 -0.3937) (xy 3.3528 -0.3937)
				(xy 3.3528 6.4008) (xy 1.4986 6.4008) (xy 1.4986 10.1473)
			)
			(stroke
				(width 0)
				(type default)
			)
			(fill no)
			(layer "F.CrtYd")
		)
		(fp_poly
			(pts
				(xy -2.0066 10.668) (xy 2.0066 10.668) (xy 2.0066 6.9088) (xy 3.8608 6.9088) (xy 3.8608 2.2098)
				(xy 3.3528 2.2098) (xy 3.3528 6.4008) (xy 1.4986 6.4008) (xy 1.4986 10.1473) (xy -1.4986 10.1473)
				(xy -1.4986 6.4008) (xy -3.3528 6.4008) (xy -3.3528 -0.3937) (xy 3.3528 -0.3937) (xy 3.3528 2.1971)
				(xy 3.8608 2.1971) (xy 3.8608 -1.143) (xy -3.8608 -1.143) (xy -3.8608 6.9088) (xy -2.0066 6.9088)
			)
			(stroke
				(width 0)
				(type default)
			)
			(fill no)
			(layer "F.CrtYd")
		)
		(fp_poly
			(pts
				(xy -2.0066 10.668) (xy -2.0066 6.9088) (xy -3.8608 6.9088) (xy -3.8608 -1.143) (xy 3.8608 -1.143)
				(xy 3.8608 6.9088) (xy 2.0066 6.9088) (xy 2.0066 10.668)
			)
			(stroke
				(width 0)
				(type default)
			)
			(fill no)
			(layer "F.Fab")
		)
		(pad "1" thru_hole circle
			(at 2.54 0 270)
			(size 1.27 1.27)
			(drill 0.889)
			(layers "*.Cu" "*.Mask")
			(remove_unused_layers no)
			(net "LED_DR_LED1_BLUE")
			(clearance 0.1651)
			(thermal_gap 0.1651)
		)
		(pad "2" thru_hole circle
			(at 0 0 270)
			(size 1.27 1.27)
			(drill 0.889)
			(layers "*.Cu" "*.Mask")
			(remove_unused_layers no)
			(net "LED_DR_LED1_K")
			(clearance 0.1651)
			(thermal_gap 0.1651)
		)
		(pad "3" thru_hole circle
			(at -2.54 0 270)
			(size 1.27 1.27)
			(drill 0.889)
			(layers "*.Cu" "*.Mask")
			(remove_unused_layers no)
			(net "LED_DR_LED1")
			(clearance 0.1651)
			(thermal_gap 0.1651)
		)
	)
	(footprint ""
		(layer "F.Cu")
		(at 34.2138 -356.185216)
		(property "Reference" "R365"
			(at 0 0 0)
			(layer "F.SilkS")
			(hide yes)
			(effects
				(font
					(size 1.27 1.27)
				)
			)
		)
		(property "Value" "10MR2J-L-GP"
			(at 0.064008 -3.993896 0)
			(unlocked yes)
			(layer "F.Fab")
			(hide yes)
			(effects
				(font
					(size 1.016 1.016)
					(thickness 0.1524)
				)
			)
		)
		(property "Device Type" "R402H16"
			(at 0.064008 -5.517896 0)
			(unlocked yes)
			(layer "F.Fab")
			(hide yes)
			(effects
				(font
					(size 1.016 1.016)
					(thickness 0.1524)
				)
			)
		)
		(duplicate_pad_numbers_are_jumpers no)
		(fp_line
			(start -0.508 -0.9398)
			(end -0.508 0.9398)
			(stroke
				(width 0.1524)
				(type default)
			)
			(layer "F.SilkS")
		)
		(fp_line
			(start 0.508 -0.9398)
			(end -0.508 -0.9398)
			(stroke
				(width 0.1524)
				(type default)
			)
			(layer "F.SilkS")
		)
		(fp_rect
			(start -0.508 0.9398)
			(end 0.508 -0.9398)
			(stroke
				(width 0)
				(type default)
			)
			(fill no)
			(layer "F.CrtYd")
		)
		(fp_rect
			(start -0.508 0.9398)
			(end 0.508 -0.9398)
			(stroke
				(width 0)
				(type default)
			)
			(fill no)
			(layer "F.Fab")
		)
		(pad "1" smd custom
			(at 0 -0.4445)
			(size 0.1397 0.1397)
			(layers "F.Cu" "F.Mask" "F.Paste")
			(net "OTP_RETRY_G")
			(options
				(clearance outline)
				(anchor circle)
			)
			(primitives
				(gr_poly
					(pts
						(arc
							(start -0.1778 -0.2794)
							(mid -0.249642 -0.249642)
							(end -0.2794 -0.1778)
						)
						(arc
							(start -0.2794 0.1778)
							(mid -0.249642 0.249642)
							(end -0.1778 0.2794)
						)
						(arc
							(start 0.1778 0.2794)
							(mid 0.249642 0.249642)
							(end 0.2794 0.1778)
						)
						(arc
							(start 0.2794 -0.1778)
							(mid 0.249642 -0.249642)
							(end 0.1778 -0.2794)
						)
					)
					(width 0)
					(fill yes)
				)
			)
		)
		(pad "2" smd custom
			(at 0 0.4445)
			(size 0.1397 0.1397)
			(layers "F.Cu" "F.Mask" "F.Paste")
			(net "GND")
			(options
				(clearance outline)
				(anchor circle)
			)
			(primitives
				(gr_poly
					(pts
						(arc
							(start -0.1778 -0.2794)
							(mid -0.249642 -0.249642)
							(end -0.2794 -0.1778)
						)
						(arc
							(start -0.2794 0.1778)
							(mid -0.249642 0.249642)
							(end -0.1778 0.2794)
						)
						(arc
							(start 0.1778 0.2794)
							(mid 0.249642 0.249642)
							(end 0.2794 0.1778)
						)
						(arc
							(start 0.2794 -0.1778)
							(mid 0.249642 -0.249642)
							(end 0.1778 -0.2794)
						)
					)
					(width 0)
					(fill yes)
				)
			)
		)
	)
	(footprint ""
		(layer "F.Cu")
		(at 41.7576 -159.1818 -90)
		(property "Reference" "R15"
			(at 0 0 270)
			(layer "F.SilkS")
			(hide yes)
			(effects
				(font
					(size 1.27 1.27)
				)
			)
		)
		(property "Value" "10KR2F-2-GP"
			(at 0.064008 -3.993896 270)
			(unlocked yes)
			(layer "F.Fab")
			(hide yes)
			(effects
				(font
					(size 1.016 1.016)
					(thickness 0.1524)
				)
			)
		)
		(property "Device Type" "R402H16"
			(at 0.064008 -5.517896 270)
			(unlocked yes)
			(layer "F.Fab")
			(hide yes)
			(effects
				(font
					(size 1.016 1.016)
					(thickness 0.1524)
				)
			)
		)
		(duplicate_pad_numbers_are_jumpers no)
		(fp_line
			(start -0.508 -0.9398)
			(end -0.508 0.9398)
			(stroke
				(width 0.1524)
				(type default)
			)
			(layer "F.SilkS")
		)
		(fp_line
			(start 0.508 -0.9398)
			(end -0.508 -0.9398)
			(stroke
				(width 0.1524)
				(type default)
			)
			(layer "F.SilkS")
		)
		(fp_rect
			(start -0.508 0.9398)
			(end 0.508 -0.9398)
			(stroke
				(width 0)
				(type default)
			)
			(fill no)
			(layer "F.CrtYd")
		)
		(fp_rect
			(start -0.508 0.9398)
			(end 0.508 -0.9398)
			(stroke
				(width 0)
				(type default)
			)
			(fill no)
			(layer "F.Fab")
		)
		(pad "1" smd custom
			(at 0 -0.4445 270)
			(size 0.1397 0.1397)
			(layers "F.Cu" "F.Mask" "F.Paste")
			(net "NCT7904_VSEN_P12V_AUX")
			(options
				(clearance outline)
				(anchor circle)
			)
			(primitives
				(gr_poly
					(pts
						(arc
							(start -0.1778 -0.2794)
							(mid -0.249642 -0.249642)
							(end -0.2794 -0.1778)
						)
						(arc
							(start -0.2794 0.1778)
							(mid -0.249642 0.249642)
							(end -0.1778 0.2794)
						)
						(arc
							(start 0.1778 0.2794)
							(mid 0.249642 0.249642)
							(end 0.2794 0.1778)
						)
						(arc
							(start 0.2794 -0.1778)
							(mid 0.249642 -0.249642)
							(end 0.1778 -0.2794)
						)
					)
					(width 0)
					(fill yes)
				)
			)
		)
		(pad "2" smd custom
			(at 0 0.4445 270)
			(size 0.1397 0.1397)
			(layers "F.Cu" "F.Mask" "F.Paste")
			(net "GND")
			(options
				(clearance outline)
				(anchor circle)
			)
			(primitives
				(gr_poly
					(pts
						(arc
							(start -0.1778 -0.2794)
							(mid -0.249642 -0.249642)
							(end -0.2794 -0.1778)
						)
						(arc
							(start -0.2794 0.1778)
							(mid -0.249642 0.249642)
							(end -0.1778 0.2794)
						)
						(arc
							(start 0.1778 0.2794)
							(mid 0.249642 0.249642)
							(end 0.2794 0.1778)
						)
						(arc
							(start 0.2794 -0.1778)
							(mid 0.249642 -0.249642)
							(end 0.1778 -0.2794)
						)
					)
					(width 0)
					(fill yes)
				)
			)
		)
	)
	(footprint ""
		(layer "F.Cu")
		(at 34.716466 -141.089634 180)
		(property "Reference" "PR107"
			(at 0 0 180)
			(layer "F.SilkS")
			(hide yes)
			(effects
				(font
					(size 1.27 1.27)
				)
			)
		)
		(property "Value" "1KR2F-3-GP"
			(at 0.064008 -3.993896 180)
			(unlocked yes)
			(layer "F.Fab")
			(hide yes)
			(effects
				(font
					(size 1.016 1.016)
					(thickness 0.1524)
				)
			)
		)
		(property "Device Type" "R402H16"
			(at 0.064008 -5.517896 180)
			(unlocked yes)
			(layer "F.Fab")
			(hide yes)
			(effects
				(font
					(size 1.016 1.016)
					(thickness 0.1524)
				)
			)
		)
		(duplicate_pad_numbers_are_jumpers no)
		(fp_line
			(start 0.508 -0.9398)
			(end -0.508 -0.9398)
			(stroke
				(width 0.1524)
				(type default)
			)
			(layer "F.SilkS")
		)
		(fp_line
			(start -0.508 -0.9398)
			(end -0.508 0.9398)
			(stroke
				(width 0.1524)
				(type default)
			)
			(layer "F.SilkS")
		)
		(fp_rect
			(start -0.508 0.9398)
			(end 0.508 -0.9398)
			(stroke
				(width 0)
				(type default)
			)
			(fill no)
			(layer "F.CrtYd")
		)
		(fp_rect
			(start -0.508 0.9398)
			(end 0.508 -0.9398)
			(stroke
				(width 0)
				(type default)
			)
			(fill no)
			(layer "F.Fab")
		)
		(pad "1" smd custom
			(at 0 -0.4445 180)
			(size 0.1397 0.1397)
			(layers "F.Cu" "F.Mask" "F.Paste")
			(net "P12VL_2490_PG")
			(options
				(clearance outline)
				(anchor circle)
			)
			(primitives
				(gr_poly
					(pts
						(arc
							(start -0.1778 -0.2794)
							(mid -0.249642 -0.249642)
							(end -0.2794 -0.1778)
						)
						(arc
							(start -0.2794 0.1778)
							(mid -0.249642 0.249642)
							(end -0.1778 0.2794)
						)
						(arc
							(start 0.1778 0.2794)
							(mid 0.249642 0.249642)
							(end 0.2794 0.1778)
						)
						(arc
							(start 0.2794 -0.1778)
							(mid 0.249642 -0.249642)
							(end 0.1778 -0.2794)
						)
					)
					(width 0)
					(fill yes)
				)
			)
		)
		(pad "2" smd custom
			(at 0 0.4445 180)
			(size 0.1397 0.1397)
			(layers "F.Cu" "F.Mask" "F.Paste")
			(net "GND")
			(options
				(clearance outline)
				(anchor circle)
			)
			(primitives
				(gr_poly
					(pts
						(arc
							(start -0.1778 -0.2794)
							(mid -0.249642 -0.249642)
							(end -0.2794 -0.1778)
						)
						(arc
							(start -0.2794 0.1778)
							(mid -0.249642 0.249642)
							(end -0.1778 0.2794)
						)
						(arc
							(start 0.1778 0.2794)
							(mid 0.249642 0.249642)
							(end 0.2794 0.1778)
						)
						(arc
							(start 0.2794 -0.1778)
							(mid 0.249642 -0.249642)
							(end 0.1778 -0.2794)
						)
					)
					(width 0)
					(fill yes)
				)
			)
		)
	)
	(footprint ""
		(layer "F.Cu")
		(at 20.3454 -245.4148 -90)
		(property "Reference" "PC41"
			(at 0 0 270)
			(layer "F.SilkS")
			(hide yes)
			(effects
				(font
					(size 1.27 1.27)
				)
			)
		)
		(property "Value" "SCD1U16V2KX-3GP"
			(at 1.1811 -2.7051 270)
			(unlocked yes)
			(layer "F.Fab")
			(hide yes)
			(effects
				(font
					(size 1.016 1.016)
					(thickness 0.1524)
				)
			)
		)
		(property "Device Type" "C402H22"
			(at 1.1811 -4.2291 270)
			(unlocked yes)
			(layer "F.Fab")
			(hide yes)
			(effects
				(font
					(size 1.016 1.016)
					(thickness 0.1524)
				)
			)
		)
		(duplicate_pad_numbers_are_jumpers no)
		(fp_rect
			(start -0.4318 0.9525)
			(end 0.4318 -0.9525)
			(stroke
				(width 0)
				(type default)
			)
			(fill no)
			(layer "F.CrtYd")
		)
		(fp_rect
			(start -0.4318 0.9525)
			(end 0.4318 -0.9525)
			(stroke
				(width 0)
				(type default)
			)
			(fill no)
			(layer "F.Fab")
		)
		(pad "1" smd custom
			(at 0 -0.4445 270)
			(size 0.1524 0.1524)
			(layers "F.Cu" "F.Mask" "F.Paste")
			(net "P3V3_BS_NET")
			(options
				(clearance outline)
				(anchor circle)
			)
			(primitives
				(gr_poly
					(pts
						(arc
							(start 0.3048 -0.2032)
							(mid 0.275042 -0.275042)
							(end 0.2032 -0.3048)
						)
						(arc
							(start -0.2032 -0.3048)
							(mid -0.275042 -0.275042)
							(end -0.3048 -0.2032)
						)
						(arc
							(start -0.3048 0.2032)
							(mid -0.275042 0.275042)
							(end -0.2032 0.3048)
						)
						(arc
							(start 0.2032 0.3048)
							(mid 0.275042 0.275042)
							(end 0.3048 0.2032)
						)
					)
					(width 0)
					(fill yes)
				)
			)
		)
		(pad "2" smd custom
			(at 0 0.4445 270)
			(size 0.1524 0.1524)
			(layers "F.Cu" "F.Mask" "F.Paste")
			(net "P3V3_LX")
			(options
				(clearance outline)
				(anchor circle)
			)
			(primitives
				(gr_poly
					(pts
						(arc
							(start 0.3048 -0.2032)
							(mid 0.275042 -0.275042)
							(end 0.2032 -0.3048)
						)
						(arc
							(start -0.2032 -0.3048)
							(mid -0.275042 -0.275042)
							(end -0.3048 -0.2032)
						)
						(arc
							(start -0.3048 0.2032)
							(mid -0.275042 0.275042)
							(end -0.2032 0.3048)
						)
						(arc
							(start 0.2032 0.3048)
							(mid 0.275042 0.275042)
							(end 0.3048 0.2032)
						)
					)
					(width 0)
					(fill yes)
				)
			)
		)
	)
	(footprint ""
		(layer "F.Cu")
		(at 18.796 -260.4516 -90)
		(property "Reference" "R80"
			(at 0 0 270)
			(layer "F.SilkS")
			(hide yes)
			(effects
				(font
					(size 1.27 1.27)
				)
			)
		)
		(property "Value" "4K7R2F-GP"
			(at 0.064008 -3.993896 270)
			(unlocked yes)
			(layer "F.Fab")
			(hide yes)
			(effects
				(font
					(size 1.016 1.016)
					(thickness 0.1524)
				)
			)
		)
		(property "Device Type" "R402H16"
			(at 0.064008 -5.517896 270)
			(unlocked yes)
			(layer "F.Fab")
			(hide yes)
			(effects
				(font
					(size 1.016 1.016)
					(thickness 0.1524)
				)
			)
		)
		(duplicate_pad_numbers_are_jumpers no)
		(fp_line
			(start -0.508 -0.9398)
			(end -0.508 0.9398)
			(stroke
				(width 0.1524)
				(type default)
			)
			(layer "F.SilkS")
		)
		(fp_line
			(start 0.508 -0.9398)
			(end -0.508 -0.9398)
			(stroke
				(width 0.1524)
				(type default)
			)
			(layer "F.SilkS")
		)
		(fp_rect
			(start -0.508 0.9398)
			(end 0.508 -0.9398)
			(stroke
				(width 0)
				(type default)
			)
			(fill no)
			(layer "F.CrtYd")
		)
		(fp_rect
			(start -0.508 0.9398)
			(end 0.508 -0.9398)
			(stroke
				(width 0)
				(type default)
			)
			(fill no)
			(layer "F.Fab")
		)
		(pad "1" smd custom
			(at 0 -0.4445 270)
			(size 0.1397 0.1397)
			(layers "F.Cu" "F.Mask" "F.Paste")
			(net "P12V")
			(options
				(clearance outline)
				(anchor circle)
			)
			(primitives
				(gr_poly
					(pts
						(arc
							(start -0.1778 -0.2794)
							(mid -0.249642 -0.249642)
							(end -0.2794 -0.1778)
						)
						(arc
							(start -0.2794 0.1778)
							(mid -0.249642 0.249642)
							(end -0.1778 0.2794)
						)
						(arc
							(start 0.1778 0.2794)
							(mid 0.249642 0.249642)
							(end 0.2794 0.1778)
						)
						(arc
							(start 0.2794 -0.1778)
							(mid 0.249642 -0.249642)
							(end 0.1778 -0.2794)
						)
					)
					(width 0)
					(fill yes)
				)
			)
		)
		(pad "2" smd custom
			(at 0 0.4445 270)
			(size 0.1397 0.1397)
			(layers "F.Cu" "F.Mask" "F.Paste")
			(net "FAN_TACH6")
			(options
				(clearance outline)
				(anchor circle)
			)
			(primitives
				(gr_poly
					(pts
						(arc
							(start -0.1778 -0.2794)
							(mid -0.249642 -0.249642)
							(end -0.2794 -0.1778)
						)
						(arc
							(start -0.2794 0.1778)
							(mid -0.249642 0.249642)
							(end -0.1778 0.2794)
						)
						(arc
							(start 0.1778 0.2794)
							(mid 0.249642 0.249642)
							(end 0.2794 0.1778)
						)
						(arc
							(start 0.2794 -0.1778)
							(mid 0.249642 -0.249642)
							(end 0.1778 -0.2794)
						)
					)
					(width 0)
					(fill yes)
				)
			)
		)
	)
)
